(kicad_pcb
	(version 20260206)
	(generator "pcbnew")
	(generator_version "10.0")
	(general
		(thickness 1.6)
		(legacy_teardrops no)
	)
	(paper "A4")
	(title_block
		(title "01162023_DA0F0TEBIF0_F0T_Expander_BD_F_brd_V02_OCP.brd")
		(comment 1 "Grand Teton / footprints 8568-8574 of 9728")
	)
	(layers
		(0 "F.Cu" signal "TOP")
		(4 "In1.Cu" signal "GND")
		(6 "In2.Cu" signal "VCC")
		(8 "In3.Cu" signal "VCC1")
		(10 "In4.Cu" signal "GND1")
		(12 "In5.Cu" signal "IN1")
		(14 "In6.Cu" signal "GND2")
		(16 "In7.Cu" signal "IN2")
		(18 "In8.Cu" signal "GND3")
		(20 "In9.Cu" signal "IN3")
		(22 "In10.Cu" signal "GND4")
		(24 "In11.Cu" signal "IN4")
		(26 "In12.Cu" signal "GND5")
		(28 "In13.Cu" signal "IN5")
		(30 "In14.Cu" signal "GND6")
		(32 "In15.Cu" signal "IN6")
		(34 "In16.Cu" signal "GND7")
		(2 "B.Cu" signal "BOTTOM")
		(9 "F.Adhes" user "F.Adhesive")
		(11 "B.Adhes" user "B.Adhesive")
		(13 "F.Paste" user "Package Geometry/Pastemask Top")
		(15 "B.Paste" user "Package Geometry/Pastemask Bottom")
		(5 "F.SilkS" user "Ref Des/Silkscreen Top")
		(7 "B.SilkS" user "Ref Des/Silkscreen Bottom")
		(1 "F.Mask" user "Board Geometry/Soldermask Top")
		(3 "B.Mask" user "Board Geometry/Soldermask Bottom")
		(17 "Dwgs.User" user "User.Drawings")
		(19 "Cmts.User" user "User.Comments")
		(21 "Eco1.User" user "User.Eco1")
		(23 "Eco2.User" user "User.Eco2")
		(25 "Edge.Cuts" user "Board Geometry/Outline")
		(27 "Margin" user)
		(31 "F.CrtYd" user "Package Geometry/Place Bound Top")
		(29 "B.CrtYd" user "Package Geometry/Place Bound Bottom")
		(35 "F.Fab" user "Ref Des/Assembly Top")
		(33 "B.Fab" user "Ref Des/Assembly Bottom")
	)
	(footprint ""
		(layer "B.Cu")
		(at 459.153768 10.715752)
		(property "Reference" "DE15T_4"
			(at 2.796032 3.026918 0)
			(unlocked yes)
			(layer "B.SilkS")
			(effects
				(font
					(size 0.7874 0.5842)
					(thickness 0.1524)
				)
				(justify left mirror)
			)
		)
		(property "Value" ""
			(at 0 0 0)
			(layer "B.Fab")
			(effects
				(font
					(size 1.27 1.27)
				)
				(justify mirror)
			)
		)
		(duplicate_pad_numbers_are_jumpers no)
		(fp_line
			(start -1.2192 -2.1082)
			(end -1.2192 2.1082)
			(stroke
				(width 0.1524)
				(type default)
			)
			(layer "B.SilkS")
		)
		(fp_line
			(start -1.2192 2.1082)
			(end 1.2192 2.1082)
			(stroke
				(width 0.1524)
				(type default)
			)
			(layer "B.SilkS")
		)
		(fp_line
			(start 1.2192 -2.1082)
			(end -1.2192 -2.1082)
			(stroke
				(width 0.1524)
				(type default)
			)
			(layer "B.SilkS")
		)
		(fp_line
			(start 1.2192 2.1082)
			(end 1.2192 -2.1082)
			(stroke
				(width 0.1524)
				(type default)
			)
			(layer "B.SilkS")
		)
		(pad "" np_thru_hole circle
			(at -3.4671 -1.27 270)
			(size 1.0414 1.0414)
			(drill 1.0414)
			(layers "*.Cu" "*.Mask")
			(clearance 0.381)
			(thermal_gap 0.381)
		)
		(pad "" np_thru_hole circle
			(at -3.4671 1.27 270)
			(size 1.0414 1.0414)
			(drill 1.0414)
			(layers "*.Cu" "*.Mask")
			(clearance 0.381)
			(thermal_gap 0.381)
		)
		(pad "" np_thru_hole circle
			(at 2.8829 -1.27 270)
			(size 1.0414 1.0414)
			(drill 1.0414)
			(layers "*.Cu" "*.Mask")
			(clearance 0.381)
			(thermal_gap 0.381)
		)
		(pad "" np_thru_hole circle
			(at 2.8829 1.27 270)
			(size 1.0414 1.0414)
			(drill 1.0414)
			(layers "*.Cu" "*.Mask")
			(clearance 0.381)
			(thermal_gap 0.381)
		)
		(pad "1" smd rect
			(at -0.8255 -0.249936 270)
			(size 0.3048 0.508)
			(layers "B.Cu" "B.Mask" "B.Paste")
			(net "85_10INCH_IN5_DN")
		)
		(pad "2" smd rect
			(at -0.8255 0.249936 270)
			(size 0.3048 0.508)
			(layers "B.Cu" "B.Mask" "B.Paste")
			(net "85_10INCH_IN5_DP")
		)
		(pad "3" smd circle
			(at 0 0 180)
			(size 0 0)
			(layers "B.Cu" "B.Mask" "B.Paste")
			(net "COUPON_GND2")
		)
		(zone
			(layers "F.Cu" "B.Cu" "In1.Cu" "In2.Cu" "In3.Cu" "In4.Cu" "In5.Cu" "In6.Cu"
				"In7.Cu" "In8.Cu" "In9.Cu" "In10.Cu" "In11.Cu" "In12.Cu" "In13.Cu" "In14.Cu"
				"In15.Cu" "In16.Cu"
			)
			(hatch none 0.5)
			(connect_pads
				(clearance 0)
			)
			(min_thickness 0.25)
			(keepout
				(tracks not_allowed)
				(vias allowed)
				(pads allowed)
				(copperpour not_allowed)
				(footprints allowed)
			)
			(placement
				(enabled no)
				(sheetname "")
			)
			(fill
				(thermal_gap 0.5)
				(thermal_bridge_width 0.5)
				(island_removal_mode 0)
			)
			(polygon
				(pts
					(arc
						(start 456.613768 9.445752)
						(mid 454.759568 9.445752)
						(end 456.613768 9.445752)
					)
				)
			)
		)
		(zone
			(layers "F.Cu" "B.Cu" "In1.Cu" "In2.Cu" "In3.Cu" "In4.Cu" "In5.Cu" "In6.Cu"
				"In7.Cu" "In8.Cu" "In9.Cu" "In10.Cu" "In11.Cu" "In12.Cu" "In13.Cu" "In14.Cu"
				"In15.Cu" "In16.Cu"
			)
			(hatch none 0.5)
			(connect_pads
				(clearance 0)
			)
			(min_thickness 0.25)
			(keepout
				(tracks not_allowed)
				(vias allowed)
				(pads allowed)
				(copperpour not_allowed)
				(footprints allowed)
			)
			(placement
				(enabled no)
				(sheetname "")
			)
			(fill
				(thermal_gap 0.5)
				(thermal_bridge_width 0.5)
				(island_removal_mode 0)
			)
			(polygon
				(pts
					(arc
						(start 456.613768 11.985752)
						(mid 454.759568 11.985752)
						(end 456.613768 11.985752)
					)
				)
			)
		)
		(zone
			(layers "F.Cu" "B.Cu" "In1.Cu" "In2.Cu" "In3.Cu" "In4.Cu" "In5.Cu" "In6.Cu"
				"In7.Cu" "In8.Cu" "In9.Cu" "In10.Cu" "In11.Cu" "In12.Cu" "In13.Cu" "In14.Cu"
				"In15.Cu" "In16.Cu"
			)
			(hatch none 0.5)
			(connect_pads
				(clearance 0)
			)
			(min_thickness 0.25)
			(keepout
				(tracks not_allowed)
				(vias allowed)
				(pads allowed)
				(copperpour not_allowed)
				(footprints allowed)
			)
			(placement
				(enabled no)
				(sheetname "")
			)
			(fill
				(thermal_gap 0.5)
				(thermal_bridge_width 0.5)
				(island_removal_mode 0)
			)
			(polygon
				(pts
					(arc
						(start 462.963768 9.445752)
						(mid 461.109568 9.445752)
						(end 462.963768 9.445752)
					)
				)
			)
		)
		(zone
			(layers "F.Cu" "B.Cu" "In1.Cu" "In2.Cu" "In3.Cu" "In4.Cu" "In5.Cu" "In6.Cu"
				"In7.Cu" "In8.Cu" "In9.Cu" "In10.Cu" "In11.Cu" "In12.Cu" "In13.Cu" "In14.Cu"
				"In15.Cu" "In16.Cu"
			)
			(hatch none 0.5)
			(connect_pads
				(clearance 0)
			)
			(min_thickness 0.25)
			(keepout
				(tracks not_allowed)
				(vias allowed)
				(pads allowed)
				(copperpour not_allowed)
				(footprints allowed)
			)
			(placement
				(enabled no)
				(sheetname "")
			)
			(fill
				(thermal_gap 0.5)
				(thermal_bridge_width 0.5)
				(island_removal_mode 0)
			)
			(polygon
				(pts
					(arc
						(start 462.963768 11.985752)
						(mid 461.109568 11.985752)
						(end 462.963768 11.985752)
					)
				)
			)
		)
		(zone
			(layer "B.Cu")
			(hatch none 0.5)
			(connect_pads
				(clearance 0)
			)
			(min_thickness 0.25)
			(keepout
				(tracks not_allowed)
				(vias allowed)
				(pads allowed)
				(copperpour not_allowed)
				(footprints allowed)
			)
			(placement
				(enabled no)
				(sheetname "")
			)
			(fill
				(thermal_gap 0.5)
				(thermal_bridge_width 0.5)
				(island_removal_mode 0)
			)
			(polygon
				(pts
					(xy 458.036168 10.167112) (xy 458.036168 10.262616) (xy 458.633068 10.262616) (xy 458.633068 10.669016)
					(xy 458.036168 10.669016) (xy 458.036168 10.762488) (xy 458.633068 10.762488) (xy 458.633068 11.168888)
					(xy 458.036168 11.168888) (xy 458.036168 11.264392) (xy 458.734668 11.264392) (xy 458.734668 10.167112)
				)
			)
		)
	)
	(footprint ""
		(layer "B.Cu")
		(at 276.649688 -292.099746)
		(property "Reference" "C3349"
			(at 0 0 0)
			(layer "B.SilkS")
			(hide yes)
			(effects
				(font
					(size 1.27 1.27)
				)
				(justify mirror)
			)
		)
		(property "Value" ""
			(at 0 0 0)
			(layer "B.Fab")
			(effects
				(font
					(size 1.27 1.27)
				)
				(justify mirror)
			)
		)
		(duplicate_pad_numbers_are_jumpers no)
		(fp_line
			(start -0.299974 -0.150114)
			(end -0.299974 0.150114)
			(stroke
				(width 0.1)
				(type default)
			)
			(layer "B.Fab")
		)
		(fp_line
			(start -0.299974 0.150114)
			(end 0.299974 0.150114)
			(stroke
				(width 0.1)
				(type default)
			)
			(layer "B.Fab")
		)
		(fp_line
			(start 0.299974 -0.150114)
			(end -0.299974 -0.150114)
			(stroke
				(width 0.1)
				(type default)
			)
			(layer "B.Fab")
		)
		(fp_line
			(start 0.299974 0.150114)
			(end 0.299974 -0.150114)
			(stroke
				(width 0.1)
				(type default)
			)
			(layer "B.Fab")
		)
		(pad "1" smd rect
			(at 0.2667 0 180)
			(size 0.3048 0.381)
			(layers "B.Cu" "B.Mask" "B.Paste")
			(net "P1V8_PEX")
		)
		(pad "2" smd rect
			(at -0.2667 0 180)
			(size 0.3048 0.381)
			(layers "B.Cu" "B.Mask" "B.Paste")
			(net "GND")
		)
	)
	(footprint ""
		(layer "B.Cu")
		(at 338.84362 -282.244292 180)
		(property "Reference" "PR7171"
			(at 0 0 0)
			(layer "B.SilkS")
			(hide yes)
			(effects
				(font
					(size 1.27 1.27)
				)
				(justify mirror)
			)
		)
		(property "Value" ""
			(at 0 0 0)
			(layer "B.Fab")
			(effects
				(font
					(size 1.27 1.27)
				)
				(justify mirror)
			)
		)
		(duplicate_pad_numbers_are_jumpers no)
		(fp_line
			(start 0.7874 0.4064)
			(end 0.7874 -0.4064)
			(stroke
				(width 0.1524)
				(type default)
			)
			(layer "B.SilkS")
		)
		(fp_line
			(start 0.7874 -0.4064)
			(end -0.7874 -0.4064)
			(stroke
				(width 0.1524)
				(type default)
			)
			(layer "B.SilkS")
		)
		(fp_line
			(start -0.7874 0.4064)
			(end 0.7874 0.4064)
			(stroke
				(width 0.1524)
				(type default)
			)
			(layer "B.SilkS")
		)
		(fp_line
			(start -0.7874 -0.4064)
			(end -0.7874 0.4064)
			(stroke
				(width 0.1524)
				(type default)
			)
			(layer "B.SilkS")
		)
		(fp_line
			(start 0.67945 0.3048)
			(end 0.67945 -0.305054)
			(stroke
				(width 0.1)
				(type default)
			)
			(layer "B.Fab")
		)
		(fp_line
			(start 0.67945 -0.305054)
			(end 0.12065 -0.305054)
			(stroke
				(width 0.1)
				(type default)
			)
			(layer "B.Fab")
		)
		(fp_line
			(start 0.12065 0.3048)
			(end 0.67945 0.3048)
			(stroke
				(width 0.1)
				(type default)
			)
			(layer "B.Fab")
		)
		(fp_line
			(start 0.12065 0.2794)
			(end 0.12065 0.3048)
			(stroke
				(width 0.1)
				(type default)
			)
			(layer "B.Fab")
		)
		(fp_line
			(start 0.12065 -0.2794)
			(end -0.12065 -0.2794)
			(stroke
				(width 0.1)
				(type default)
			)
			(layer "B.Fab")
		)
		(fp_line
			(start 0.12065 -0.305054)
			(end 0.12065 -0.2794)
			(stroke
				(width 0.1)
				(type default)
			)
			(layer "B.Fab")
		)
		(fp_line
			(start -0.120396 0.3048)
			(end -0.120396 0.2794)
			(stroke
				(width 0.1)
				(type default)
			)
			(layer "B.Fab")
		)
		(fp_line
			(start -0.120396 0.2794)
			(end 0.12065 0.2794)
			(stroke
				(width 0.1)
				(type default)
			)
			(layer "B.Fab")
		)
		(fp_line
			(start -0.12065 -0.2794)
			(end -0.12065 -0.3048)
			(stroke
				(width 0.1)
				(type default)
			)
			(layer "B.Fab")
		)
		(fp_line
			(start -0.12065 -0.3048)
			(end -0.67945 -0.3048)
			(stroke
				(width 0.1)
				(type default)
			)
			(layer "B.Fab")
		)
		(fp_line
			(start -0.67945 0.3048)
			(end -0.120396 0.3048)
			(stroke
				(width 0.1)
				(type default)
			)
			(layer "B.Fab")
		)
		(fp_line
			(start -0.67945 -0.3048)
			(end -0.67945 0.3048)
			(stroke
				(width 0.1)
				(type default)
			)
			(layer "B.Fab")
		)
		(pad "1" smd circle
			(at 0.40005 0)
			(size 0 0)
			(layers "B.Cu" "B.Mask" "B.Paste")
			(net "P0V8_PEX2_EN1")
		)
		(pad "2" smd circle
			(at -0.40005 0)
			(size 0 0)
			(layers "B.Cu" "B.Mask" "B.Paste")
			(net "P0V8_PEX2_VCC1")
		)
	)
	(footprint ""
		(layer "B.Cu")
		(at 203.707492 -374.031764 -90)
		(property "Reference" "PR5"
			(at 0 0 90)
			(layer "B.SilkS")
			(hide yes)
			(effects
				(font
					(size 1.27 1.27)
				)
				(justify mirror)
			)
		)
		(property "Value" ""
			(at 0 0 90)
			(layer "B.Fab")
			(effects
				(font
					(size 1.27 1.27)
				)
				(justify mirror)
			)
		)
		(duplicate_pad_numbers_are_jumpers no)
		(fp_line
			(start -0.7874 0.4064)
			(end 0.7874 0.4064)
			(stroke
				(width 0.1524)
				(type default)
			)
			(layer "B.SilkS")
		)
		(fp_line
			(start 0.7874 0.4064)
			(end 0.7874 -0.4064)
			(stroke
				(width 0.1524)
				(type default)
			)
			(layer "B.SilkS")
		)
		(fp_line
			(start -0.7874 -0.4064)
			(end -0.7874 0.4064)
			(stroke
				(width 0.1524)
				(type default)
			)
			(layer "B.SilkS")
		)
		(fp_line
			(start 0.7874 -0.4064)
			(end -0.7874 -0.4064)
			(stroke
				(width 0.1524)
				(type default)
			)
			(layer "B.SilkS")
		)
		(fp_line
			(start -0.67945 0.3048)
			(end -0.120396 0.3048)
			(stroke
				(width 0.1)
				(type default)
			)
			(layer "B.Fab")
		)
		(fp_line
			(start -0.120396 0.3048)
			(end -0.120396 0.2794)
			(stroke
				(width 0.1)
				(type default)
			)
			(layer "B.Fab")
		)
		(fp_line
			(start 0.12065 0.3048)
			(end 0.67945 0.3048)
			(stroke
				(width 0.1)
				(type default)
			)
			(layer "B.Fab")
		)
		(fp_line
			(start 0.67945 0.3048)
			(end 0.67945 -0.305054)
			(stroke
				(width 0.1)
				(type default)
			)
			(layer "B.Fab")
		)
		(fp_line
			(start -0.120396 0.2794)
			(end 0.12065 0.2794)
			(stroke
				(width 0.1)
				(type default)
			)
			(layer "B.Fab")
		)
		(fp_line
			(start 0.12065 0.2794)
			(end 0.12065 0.3048)
			(stroke
				(width 0.1)
				(type default)
			)
			(layer "B.Fab")
		)
		(fp_line
			(start -0.12065 -0.2794)
			(end -0.12065 -0.3048)
			(stroke
				(width 0.1)
				(type default)
			)
			(layer "B.Fab")
		)
		(fp_line
			(start 0.12065 -0.2794)
			(end -0.12065 -0.2794)
			(stroke
				(width 0.1)
				(type default)
			)
			(layer "B.Fab")
		)
		(fp_line
			(start -0.67945 -0.3048)
			(end -0.67945 0.3048)
			(stroke
				(width 0.1)
				(type default)
			)
			(layer "B.Fab")
		)
		(fp_line
			(start -0.12065 -0.3048)
			(end -0.67945 -0.3048)
			(stroke
				(width 0.1)
				(type default)
			)
			(layer "B.Fab")
		)
		(fp_line
			(start 0.12065 -0.305054)
			(end 0.12065 -0.2794)
			(stroke
				(width 0.1)
				(type default)
			)
			(layer "B.Fab")
		)
		(fp_line
			(start 0.67945 -0.305054)
			(end 0.12065 -0.305054)
			(stroke
				(width 0.1)
				(type default)
			)
			(layer "B.Fab")
		)
		(pad "1" smd circle
			(at 0.40005 0 90)
			(size 0 0)
			(layers "B.Cu" "B.Mask" "B.Paste")
			(net "HSC_VINSEN")
		)
		(pad "2" smd circle
			(at -0.40005 0 90)
			(size 0 0)
			(layers "B.Cu" "B.Mask" "B.Paste")
			(net "AGND_HSC")
		)
	)
	(footprint ""
		(layer "B.Cu")
		(at 401.299934 -292.099746 90)
		(property "Reference" "C1955"
			(at 0 0 90)
			(layer "B.SilkS")
			(hide yes)
			(effects
				(font
					(size 1.27 1.27)
				)
				(justify mirror)
			)
		)
		(property "Value" ""
			(at 0 0 90)
			(layer "B.Fab")
			(effects
				(font
					(size 1.27 1.27)
				)
				(justify mirror)
			)
		)
		(duplicate_pad_numbers_are_jumpers no)
		(fp_line
			(start 0.299974 -0.150114)
			(end -0.299974 -0.150114)
			(stroke
				(width 0.1)
				(type default)
			)
			(layer "B.Fab")
		)
		(fp_line
			(start -0.299974 -0.150114)
			(end -0.299974 0.150114)
			(stroke
				(width 0.1)
				(type default)
			)
			(layer "B.Fab")
		)
		(fp_line
			(start 0.299974 0.150114)
			(end 0.299974 -0.150114)
			(stroke
				(width 0.1)
				(type default)
			)
			(layer "B.Fab")
		)
		(fp_line
			(start -0.299974 0.150114)
			(end 0.299974 0.150114)
			(stroke
				(width 0.1)
				(type default)
			)
			(layer "B.Fab")
		)
		(pad "1" smd rect
			(at 0.2667 0 270)
			(size 0.3048 0.381)
			(layers "B.Cu" "B.Mask" "B.Paste")
			(net "P0V8_SERDES_VDDA_PEX3")
		)
		(pad "2" smd rect
			(at -0.2667 0 270)
			(size 0.3048 0.381)
			(layers "B.Cu" "B.Mask" "B.Paste")
			(net "GND")
		)
	)
	(footprint ""
		(layer "B.Cu")
		(at 394.164312 -142.795752 180)
		(property "Reference" "C937"
			(at 0 0 0)
			(layer "B.SilkS")
			(hide yes)
			(effects
				(font
					(size 1.27 1.27)
				)
				(justify mirror)
			)
		)
		(property "Value" ""
			(at 0 0 0)
			(layer "B.Fab")
			(effects
				(font
					(size 1.27 1.27)
				)
				(justify mirror)
			)
		)
		(duplicate_pad_numbers_are_jumpers no)
		(fp_line
			(start 0.299974 0.150114)
			(end 0.299974 -0.150114)
			(stroke
				(width 0.1)
				(type default)
			)
			(layer "B.Fab")
		)
		(fp_line
			(start 0.299974 -0.150114)
			(end -0.299974 -0.150114)
			(stroke
				(width 0.1)
				(type default)
			)
			(layer "B.Fab")
		)
		(fp_line
			(start -0.299974 0.150114)
			(end 0.299974 0.150114)
			(stroke
				(width 0.1)
				(type default)
			)
			(layer "B.Fab")
		)
		(fp_line
			(start -0.299974 -0.150114)
			(end -0.299974 0.150114)
			(stroke
				(width 0.1)
				(type default)
			)
			(layer "B.Fab")
		)
		(pad "1" smd rect
			(at 0.2667 0)
			(size 0.3048 0.381)
			(layers "B.Cu" "B.Mask" "B.Paste")
			(net "P12V_NIC6")
		)
		(pad "2" smd rect
			(at -0.2667 0)
			(size 0.3048 0.381)
			(layers "B.Cu" "B.Mask" "B.Paste")
			(net "GND")
		)
	)
	(footprint ""
		(layer "B.Cu")
		(at 302.299878 -290.674806 180)
		(property "Reference" "C3341"
			(at 0 0 0)
			(layer "B.SilkS")
			(hide yes)
			(effects
				(font
					(size 1.27 1.27)
				)
				(justify mirror)
			)
		)
		(property "Value" ""
			(at 0 0 0)
			(layer "B.Fab")
			(effects
				(font
					(size 1.27 1.27)
				)
				(justify mirror)
			)
		)
		(duplicate_pad_numbers_are_jumpers no)
		(fp_line
			(start 0.299974 0.150114)
			(end 0.299974 -0.150114)
			(stroke
				(width 0.1)
				(type default)
			)
			(layer "B.Fab")
		)
		(fp_line
			(start 0.299974 -0.150114)
			(end -0.299974 -0.150114)
			(stroke
				(width 0.1)
				(type default)
			)
			(layer "B.Fab")
		)
		(fp_line
			(start -0.299974 0.150114)
			(end 0.299974 0.150114)
			(stroke
				(width 0.1)
				(type default)
			)
			(layer "B.Fab")
		)
		(fp_line
			(start -0.299974 -0.150114)
			(end -0.299974 0.150114)
			(stroke
				(width 0.1)
				(type default)
			)
			(layer "B.Fab")
		)
		(pad "1" smd rect
			(at 0.2667 0)
			(size 0.3048 0.381)
			(layers "B.Cu" "B.Mask" "B.Paste")
			(net "P1V8_PEX")
		)
		(pad "2" smd rect
			(at -0.2667 0)
			(size 0.3048 0.381)
			(layers "B.Cu" "B.Mask" "B.Paste")
			(net "GND")
		)
	)
)
